(kicad_pcb
	(version 20260206)
	(generator "pcbnew")
	(generator_version "10.0")
	(general
		(thickness 1.6)
		(legacy_teardrops no)
	)
	(paper "A4")
	(title_block
		(title "01162023_DA0F0TEBIF0_F0T_Expander_BD_F_brd_V02_OCP.brd")
		(comment 1 "Grand Teton / footprints 7587-7595 of 9728")
	)
	(layers
		(0 "F.Cu" signal "TOP")
		(4 "In1.Cu" signal "GND")
		(6 "In2.Cu" signal "VCC")
		(8 "In3.Cu" signal "VCC1")
		(10 "In4.Cu" signal "GND1")
		(12 "In5.Cu" signal "IN1")
		(14 "In6.Cu" signal "GND2")
		(16 "In7.Cu" signal "IN2")
		(18 "In8.Cu" signal "GND3")
		(20 "In9.Cu" signal "IN3")
		(22 "In10.Cu" signal "GND4")
		(24 "In11.Cu" signal "IN4")
		(26 "In12.Cu" signal "GND5")
		(28 "In13.Cu" signal "IN5")
		(30 "In14.Cu" signal "GND6")
		(32 "In15.Cu" signal "IN6")
		(34 "In16.Cu" signal "GND7")
		(2 "B.Cu" signal "BOTTOM")
		(9 "F.Adhes" user "F.Adhesive")
		(11 "B.Adhes" user "B.Adhesive")
		(13 "F.Paste" user "Package Geometry/Pastemask Top")
		(15 "B.Paste" user "Package Geometry/Pastemask Bottom")
		(5 "F.SilkS" user "Ref Des/Silkscreen Top")
		(7 "B.SilkS" user "Ref Des/Silkscreen Bottom")
		(1 "F.Mask" user "Board Geometry/Soldermask Top")
		(3 "B.Mask" user "Board Geometry/Soldermask Bottom")
		(17 "Dwgs.User" user "User.Drawings")
		(19 "Cmts.User" user "User.Comments")
		(21 "Eco1.User" user "User.Eco1")
		(23 "Eco2.User" user "User.Eco2")
		(25 "Edge.Cuts" user "Board Geometry/Outline")
		(27 "Margin" user)
		(31 "F.CrtYd" user "Package Geometry/Place Bound Top")
		(29 "B.CrtYd" user "Package Geometry/Place Bound Bottom")
		(35 "F.Fab" user "Ref Des/Assembly Top")
		(33 "B.Fab" user "Ref Des/Assembly Bottom")
	)
	(footprint ""
		(layer "B.Cu")
		(at 144.841214 -204.380846 -90)
		(property "Reference" "C2589"
			(at 0 0 90)
			(layer "B.SilkS")
			(hide yes)
			(effects
				(font
					(size 1.27 1.27)
				)
				(justify mirror)
			)
		)
		(property "Value" ""
			(at 0 0 90)
			(layer "B.Fab")
			(effects
				(font
					(size 1.27 1.27)
				)
				(justify mirror)
			)
		)
		(duplicate_pad_numbers_are_jumpers no)
		(fp_line
			(start -0.7874 0.4064)
			(end 0.7874 0.4064)
			(stroke
				(width 0.1524)
				(type default)
			)
			(layer "B.SilkS")
		)
		(fp_line
			(start 0.7874 0.4064)
			(end 0.7874 -0.4064)
			(stroke
				(width 0.1524)
				(type default)
			)
			(layer "B.SilkS")
		)
		(fp_line
			(start -0.7874 -0.4064)
			(end -0.7874 0.4064)
			(stroke
				(width 0.1524)
				(type default)
			)
			(layer "B.SilkS")
		)
		(fp_line
			(start 0.7874 -0.4064)
			(end -0.7874 -0.4064)
			(stroke
				(width 0.1524)
				(type default)
			)
			(layer "B.SilkS")
		)
		(fp_line
			(start -0.67945 0.3048)
			(end -0.120396 0.3048)
			(stroke
				(width 0.1)
				(type default)
			)
			(layer "B.Fab")
		)
		(fp_line
			(start -0.120396 0.3048)
			(end -0.120396 0.2794)
			(stroke
				(width 0.1)
				(type default)
			)
			(layer "B.Fab")
		)
		(fp_line
			(start 0.12065 0.3048)
			(end 0.67945 0.3048)
			(stroke
				(width 0.1)
				(type default)
			)
			(layer "B.Fab")
		)
		(fp_line
			(start 0.67945 0.3048)
			(end 0.67945 -0.305054)
			(stroke
				(width 0.1)
				(type default)
			)
			(layer "B.Fab")
		)
		(fp_line
			(start -0.120396 0.2794)
			(end 0.12065 0.2794)
			(stroke
				(width 0.1)
				(type default)
			)
			(layer "B.Fab")
		)
		(fp_line
			(start 0.12065 0.2794)
			(end 0.12065 0.3048)
			(stroke
				(width 0.1)
				(type default)
			)
			(layer "B.Fab")
		)
		(fp_line
			(start -0.12065 -0.2794)
			(end -0.12065 -0.3048)
			(stroke
				(width 0.1)
				(type default)
			)
			(layer "B.Fab")
		)
		(fp_line
			(start 0.12065 -0.2794)
			(end -0.12065 -0.2794)
			(stroke
				(width 0.1)
				(type default)
			)
			(layer "B.Fab")
		)
		(fp_line
			(start -0.67945 -0.3048)
			(end -0.67945 0.3048)
			(stroke
				(width 0.1)
				(type default)
			)
			(layer "B.Fab")
		)
		(fp_line
			(start -0.12065 -0.3048)
			(end -0.67945 -0.3048)
			(stroke
				(width 0.1)
				(type default)
			)
			(layer "B.Fab")
		)
		(fp_line
			(start 0.12065 -0.305054)
			(end 0.12065 -0.2794)
			(stroke
				(width 0.1)
				(type default)
			)
			(layer "B.Fab")
		)
		(fp_line
			(start 0.67945 -0.305054)
			(end 0.12065 -0.305054)
			(stroke
				(width 0.1)
				(type default)
			)
			(layer "B.Fab")
		)
		(pad "1" smd circle
			(at 0.40005 0 90)
			(size 0 0)
			(layers "B.Cu" "B.Mask" "B.Paste")
			(net "P3V3_AUX")
		)
		(pad "2" smd circle
			(at -0.40005 0 90)
			(size 0 0)
			(layers "B.Cu" "B.Mask" "B.Paste")
			(net "GND")
		)
	)
	(footprint ""
		(layer "B.Cu")
		(at 118.688358 -277.639272)
		(property "Reference" "PC6611"
			(at 0 0 0)
			(layer "B.SilkS")
			(hide yes)
			(effects
				(font
					(size 1.27 1.27)
				)
				(justify mirror)
			)
		)
		(property "Value" ""
			(at 0 0 0)
			(layer "B.Fab")
			(effects
				(font
					(size 1.27 1.27)
				)
				(justify mirror)
			)
		)
		(duplicate_pad_numbers_are_jumpers no)
		(fp_line
			(start -1.524 -0.762)
			(end -1.524 0.762)
			(stroke
				(width 0.1524)
				(type default)
			)
			(layer "B.SilkS")
		)
		(fp_line
			(start -1.524 0.762)
			(end 1.524 0.762)
			(stroke
				(width 0.1524)
				(type default)
			)
			(layer "B.SilkS")
		)
		(fp_line
			(start 1.524 -0.762)
			(end -1.524 -0.762)
			(stroke
				(width 0.1524)
				(type default)
			)
			(layer "B.SilkS")
		)
		(fp_line
			(start 1.524 0.762)
			(end 1.524 -0.762)
			(stroke
				(width 0.1524)
				(type default)
			)
			(layer "B.SilkS")
		)
		(fp_line
			(start -1.1049 -0.724916)
			(end 1.1049 -0.724916)
			(stroke
				(width 0.1)
				(type default)
			)
			(layer "B.Fab")
		)
		(fp_line
			(start -1.1049 0.724916)
			(end -1.1049 -0.724916)
			(stroke
				(width 0.1)
				(type default)
			)
			(layer "B.Fab")
		)
		(fp_line
			(start 1.1049 -0.724916)
			(end 1.1049 0.724916)
			(stroke
				(width 0.1)
				(type default)
			)
			(layer "B.Fab")
		)
		(fp_line
			(start 1.1049 0.724916)
			(end -1.1049 0.724916)
			(stroke
				(width 0.1)
				(type default)
			)
			(layer "B.Fab")
		)
		(pad "1" smd rect
			(at 0.889 0)
			(size 1.016 1.27)
			(layers "B.Cu" "B.Mask" "B.Paste")
			(net "SW_P12V_P0V8_PEX1_FLT")
		)
		(pad "2" smd rect
			(at -0.889 0)
			(size 1.016 1.27)
			(layers "B.Cu" "B.Mask" "B.Paste")
			(net "GND")
		)
	)
	(footprint ""
		(layer "B.Cu")
		(at 138.618214 -203.237846 -90)
		(property "Reference" "R917"
			(at 0 0 90)
			(layer "B.SilkS")
			(hide yes)
			(effects
				(font
					(size 1.27 1.27)
				)
				(justify mirror)
			)
		)
		(property "Value" ""
			(at 0 0 90)
			(layer "B.Fab")
			(effects
				(font
					(size 1.27 1.27)
				)
				(justify mirror)
			)
		)
		(duplicate_pad_numbers_are_jumpers no)
		(fp_line
			(start -0.7874 0.4064)
			(end 0.7874 0.4064)
			(stroke
				(width 0.1524)
				(type default)
			)
			(layer "B.SilkS")
		)
		(fp_line
			(start 0.7874 0.4064)
			(end 0.7874 -0.4064)
			(stroke
				(width 0.1524)
				(type default)
			)
			(layer "B.SilkS")
		)
		(fp_line
			(start -0.7874 -0.4064)
			(end -0.7874 0.4064)
			(stroke
				(width 0.1524)
				(type default)
			)
			(layer "B.SilkS")
		)
		(fp_line
			(start 0.7874 -0.4064)
			(end -0.7874 -0.4064)
			(stroke
				(width 0.1524)
				(type default)
			)
			(layer "B.SilkS")
		)
		(fp_line
			(start -0.67945 0.3048)
			(end -0.120396 0.3048)
			(stroke
				(width 0.1)
				(type default)
			)
			(layer "B.Fab")
		)
		(fp_line
			(start -0.120396 0.3048)
			(end -0.120396 0.2794)
			(stroke
				(width 0.1)
				(type default)
			)
			(layer "B.Fab")
		)
		(fp_line
			(start 0.12065 0.3048)
			(end 0.67945 0.3048)
			(stroke
				(width 0.1)
				(type default)
			)
			(layer "B.Fab")
		)
		(fp_line
			(start 0.67945 0.3048)
			(end 0.67945 -0.305054)
			(stroke
				(width 0.1)
				(type default)
			)
			(layer "B.Fab")
		)
		(fp_line
			(start -0.120396 0.2794)
			(end 0.12065 0.2794)
			(stroke
				(width 0.1)
				(type default)
			)
			(layer "B.Fab")
		)
		(fp_line
			(start 0.12065 0.2794)
			(end 0.12065 0.3048)
			(stroke
				(width 0.1)
				(type default)
			)
			(layer "B.Fab")
		)
		(fp_line
			(start -0.12065 -0.2794)
			(end -0.12065 -0.3048)
			(stroke
				(width 0.1)
				(type default)
			)
			(layer "B.Fab")
		)
		(fp_line
			(start 0.12065 -0.2794)
			(end -0.12065 -0.2794)
			(stroke
				(width 0.1)
				(type default)
			)
			(layer "B.Fab")
		)
		(fp_line
			(start -0.67945 -0.3048)
			(end -0.67945 0.3048)
			(stroke
				(width 0.1)
				(type default)
			)
			(layer "B.Fab")
		)
		(fp_line
			(start -0.12065 -0.3048)
			(end -0.67945 -0.3048)
			(stroke
				(width 0.1)
				(type default)
			)
			(layer "B.Fab")
		)
		(fp_line
			(start 0.12065 -0.305054)
			(end 0.12065 -0.2794)
			(stroke
				(width 0.1)
				(type default)
			)
			(layer "B.Fab")
		)
		(fp_line
			(start 0.67945 -0.305054)
			(end 0.12065 -0.305054)
			(stroke
				(width 0.1)
				(type default)
			)
			(layer "B.Fab")
		)
		(pad "1" smd circle
			(at 0.40005 0 90)
			(size 0 0)
			(layers "B.Cu" "B.Mask" "B.Paste")
			(net "FT4232_CLI_REF")
		)
		(pad "2" smd circle
			(at -0.40005 0 90)
			(size 0 0)
			(layers "B.Cu" "B.Mask" "B.Paste")
			(net "GND")
		)
	)
	(footprint ""
		(layer "B.Cu")
		(at 115.919758 -260.400546 -90)
		(property "Reference" "PR95"
			(at 0 0 90)
			(layer "B.SilkS")
			(hide yes)
			(effects
				(font
					(size 1.27 1.27)
				)
				(justify mirror)
			)
		)
		(property "Value" ""
			(at 0 0 90)
			(layer "B.Fab")
			(effects
				(font
					(size 1.27 1.27)
				)
				(justify mirror)
			)
		)
		(duplicate_pad_numbers_are_jumpers no)
		(fp_line
			(start -0.7874 0.4064)
			(end 0.7874 0.4064)
			(stroke
				(width 0.1524)
				(type default)
			)
			(layer "B.SilkS")
		)
		(fp_line
			(start 0.7874 0.4064)
			(end 0.7874 -0.4064)
			(stroke
				(width 0.1524)
				(type default)
			)
			(layer "B.SilkS")
		)
		(fp_line
			(start -0.7874 -0.4064)
			(end -0.7874 0.4064)
			(stroke
				(width 0.1524)
				(type default)
			)
			(layer "B.SilkS")
		)
		(fp_line
			(start 0.7874 -0.4064)
			(end -0.7874 -0.4064)
			(stroke
				(width 0.1524)
				(type default)
			)
			(layer "B.SilkS")
		)
		(fp_line
			(start -0.67945 0.3048)
			(end -0.120396 0.3048)
			(stroke
				(width 0.1)
				(type default)
			)
			(layer "B.Fab")
		)
		(fp_line
			(start -0.120396 0.3048)
			(end -0.120396 0.2794)
			(stroke
				(width 0.1)
				(type default)
			)
			(layer "B.Fab")
		)
		(fp_line
			(start 0.12065 0.3048)
			(end 0.67945 0.3048)
			(stroke
				(width 0.1)
				(type default)
			)
			(layer "B.Fab")
		)
		(fp_line
			(start 0.67945 0.3048)
			(end 0.67945 -0.305054)
			(stroke
				(width 0.1)
				(type default)
			)
			(layer "B.Fab")
		)
		(fp_line
			(start -0.120396 0.2794)
			(end 0.12065 0.2794)
			(stroke
				(width 0.1)
				(type default)
			)
			(layer "B.Fab")
		)
		(fp_line
			(start 0.12065 0.2794)
			(end 0.12065 0.3048)
			(stroke
				(width 0.1)
				(type default)
			)
			(layer "B.Fab")
		)
		(fp_line
			(start -0.12065 -0.2794)
			(end -0.12065 -0.3048)
			(stroke
				(width 0.1)
				(type default)
			)
			(layer "B.Fab")
		)
		(fp_line
			(start 0.12065 -0.2794)
			(end -0.12065 -0.2794)
			(stroke
				(width 0.1)
				(type default)
			)
			(layer "B.Fab")
		)
		(fp_line
			(start -0.67945 -0.3048)
			(end -0.67945 0.3048)
			(stroke
				(width 0.1)
				(type default)
			)
			(layer "B.Fab")
		)
		(fp_line
			(start -0.12065 -0.3048)
			(end -0.67945 -0.3048)
			(stroke
				(width 0.1)
				(type default)
			)
			(layer "B.Fab")
		)
		(fp_line
			(start 0.12065 -0.305054)
			(end 0.12065 -0.2794)
			(stroke
				(width 0.1)
				(type default)
			)
			(layer "B.Fab")
		)
		(fp_line
			(start 0.67945 -0.305054)
			(end 0.12065 -0.305054)
			(stroke
				(width 0.1)
				(type default)
			)
			(layer "B.Fab")
		)
		(pad "1" smd circle
			(at 0.40005 0 90)
			(size 0 0)
			(layers "B.Cu" "B.Mask" "B.Paste")
			(net "P0V8_PEX0_TSEN_R")
		)
		(pad "2" smd circle
			(at -0.40005 0 90)
			(size 0 0)
			(layers "B.Cu" "B.Mask" "B.Paste")
			(net "P0V8_PEX0_TSEN")
		)
	)
	(footprint ""
		(layer "B.Cu")
		(at 364.453932 -223.937068 90)
		(property "Reference" "R3497"
			(at 0 0 90)
			(layer "B.SilkS")
			(hide yes)
			(effects
				(font
					(size 1.27 1.27)
				)
				(justify mirror)
			)
		)
		(property "Value" ""
			(at 0 0 90)
			(layer "B.Fab")
			(effects
				(font
					(size 1.27 1.27)
				)
				(justify mirror)
			)
		)
		(duplicate_pad_numbers_are_jumpers no)
		(fp_line
			(start 0.7874 -0.4064)
			(end -0.7874 -0.4064)
			(stroke
				(width 0.1524)
				(type default)
			)
			(layer "B.SilkS")
		)
		(fp_line
			(start -0.7874 -0.4064)
			(end -0.7874 0.4064)
			(stroke
				(width 0.1524)
				(type default)
			)
			(layer "B.SilkS")
		)
		(fp_line
			(start 0.7874 0.4064)
			(end 0.7874 -0.4064)
			(stroke
				(width 0.1524)
				(type default)
			)
			(layer "B.SilkS")
		)
		(fp_line
			(start -0.7874 0.4064)
			(end 0.7874 0.4064)
			(stroke
				(width 0.1524)
				(type default)
			)
			(layer "B.SilkS")
		)
		(fp_line
			(start 0.67945 -0.305054)
			(end 0.12065 -0.305054)
			(stroke
				(width 0.1)
				(type default)
			)
			(layer "B.Fab")
		)
		(fp_line
			(start 0.12065 -0.305054)
			(end 0.12065 -0.2794)
			(stroke
				(width 0.1)
				(type default)
			)
			(layer "B.Fab")
		)
		(fp_line
			(start -0.12065 -0.3048)
			(end -0.67945 -0.3048)
			(stroke
				(width 0.1)
				(type default)
			)
			(layer "B.Fab")
		)
		(fp_line
			(start -0.67945 -0.3048)
			(end -0.67945 0.3048)
			(stroke
				(width 0.1)
				(type default)
			)
			(layer "B.Fab")
		)
		(fp_line
			(start 0.12065 -0.2794)
			(end -0.12065 -0.2794)
			(stroke
				(width 0.1)
				(type default)
			)
			(layer "B.Fab")
		)
		(fp_line
			(start -0.12065 -0.2794)
			(end -0.12065 -0.3048)
			(stroke
				(width 0.1)
				(type default)
			)
			(layer "B.Fab")
		)
		(fp_line
			(start 0.12065 0.2794)
			(end 0.12065 0.3048)
			(stroke
				(width 0.1)
				(type default)
			)
			(layer "B.Fab")
		)
		(fp_line
			(start -0.120396 0.2794)
			(end 0.12065 0.2794)
			(stroke
				(width 0.1)
				(type default)
			)
			(layer "B.Fab")
		)
		(fp_line
			(start 0.67945 0.3048)
			(end 0.67945 -0.305054)
			(stroke
				(width 0.1)
				(type default)
			)
			(layer "B.Fab")
		)
		(fp_line
			(start 0.12065 0.3048)
			(end 0.67945 0.3048)
			(stroke
				(width 0.1)
				(type default)
			)
			(layer "B.Fab")
		)
		(fp_line
			(start -0.120396 0.3048)
			(end -0.120396 0.2794)
			(stroke
				(width 0.1)
				(type default)
			)
			(layer "B.Fab")
		)
		(fp_line
			(start -0.67945 0.3048)
			(end -0.120396 0.3048)
			(stroke
				(width 0.1)
				(type default)
			)
			(layer "B.Fab")
		)
		(pad "1" smd circle
			(at 0.40005 0 270)
			(size 0 0)
			(layers "B.Cu" "B.Mask" "B.Paste")
			(net "SPI_MUX_PEX3_EN_N")
		)
		(pad "2" smd circle
			(at -0.40005 0 270)
			(size 0 0)
			(layers "B.Cu" "B.Mask" "B.Paste")
			(net "GND")
		)
	)
	(footprint ""
		(layer "B.Cu")
		(at 180.50002 -301.599854 -90)
		(property "Reference" "C1475"
			(at 0 0 90)
			(layer "B.SilkS")
			(hide yes)
			(effects
				(font
					(size 1.27 1.27)
				)
				(justify mirror)
			)
		)
		(property "Value" ""
			(at 0 0 90)
			(layer "B.Fab")
			(effects
				(font
					(size 1.27 1.27)
				)
				(justify mirror)
			)
		)
		(duplicate_pad_numbers_are_jumpers no)
		(fp_line
			(start -0.299974 0.150114)
			(end 0.299974 0.150114)
			(stroke
				(width 0.1)
				(type default)
			)
			(layer "B.Fab")
		)
		(fp_line
			(start 0.299974 0.150114)
			(end 0.299974 -0.150114)
			(stroke
				(width 0.1)
				(type default)
			)
			(layer "B.Fab")
		)
		(fp_line
			(start -0.299974 -0.150114)
			(end -0.299974 0.150114)
			(stroke
				(width 0.1)
				(type default)
			)
			(layer "B.Fab")
		)
		(fp_line
			(start 0.299974 -0.150114)
			(end -0.299974 -0.150114)
			(stroke
				(width 0.1)
				(type default)
			)
			(layer "B.Fab")
		)
		(pad "1" smd rect
			(at 0.2667 0 90)
			(size 0.3048 0.381)
			(layers "B.Cu" "B.Mask" "B.Paste")
			(net "P0V8_SERDES_VDDA_PEX1")
		)
		(pad "2" smd rect
			(at -0.2667 0 90)
			(size 0.3048 0.381)
			(layers "B.Cu" "B.Mask" "B.Paste")
			(net "GND")
		)
	)
	(footprint ""
		(layer "B.Cu")
		(at 419.349936 -293.52494 180)
		(property "Reference" "C3452"
			(at 0 0 0)
			(layer "B.SilkS")
			(hide yes)
			(effects
				(font
					(size 1.27 1.27)
				)
				(justify mirror)
			)
		)
		(property "Value" ""
			(at 0 0 0)
			(layer "B.Fab")
			(effects
				(font
					(size 1.27 1.27)
				)
				(justify mirror)
			)
		)
		(duplicate_pad_numbers_are_jumpers no)
		(fp_line
			(start 0.299974 0.150114)
			(end 0.299974 -0.150114)
			(stroke
				(width 0.1)
				(type default)
			)
			(layer "B.Fab")
		)
		(fp_line
			(start 0.299974 -0.150114)
			(end -0.299974 -0.150114)
			(stroke
				(width 0.1)
				(type default)
			)
			(layer "B.Fab")
		)
		(fp_line
			(start -0.299974 0.150114)
			(end 0.299974 0.150114)
			(stroke
				(width 0.1)
				(type default)
			)
			(layer "B.Fab")
		)
		(fp_line
			(start -0.299974 -0.150114)
			(end -0.299974 0.150114)
			(stroke
				(width 0.1)
				(type default)
			)
			(layer "B.Fab")
		)
		(pad "1" smd rect
			(at 0.2667 0)
			(size 0.3048 0.381)
			(layers "B.Cu" "B.Mask" "B.Paste")
			(net "P1V25_PEX3")
		)
		(pad "2" smd rect
			(at -0.2667 0)
			(size 0.3048 0.381)
			(layers "B.Cu" "B.Mask" "B.Paste")
			(net "GND")
		)
	)
	(footprint ""
		(layer "B.Cu")
		(at 69.149976 -302.074834)
		(property "Reference" "C2992"
			(at 0 0 0)
			(layer "B.SilkS")
			(hide yes)
			(effects
				(font
					(size 1.27 1.27)
				)
				(justify mirror)
			)
		)
		(property "Value" ""
			(at 0 0 0)
			(layer "B.Fab")
			(effects
				(font
					(size 1.27 1.27)
				)
				(justify mirror)
			)
		)
		(duplicate_pad_numbers_are_jumpers no)
		(fp_line
			(start -0.299974 -0.150114)
			(end -0.299974 0.150114)
			(stroke
				(width 0.1)
				(type default)
			)
			(layer "B.Fab")
		)
		(fp_line
			(start -0.299974 0.150114)
			(end 0.299974 0.150114)
			(stroke
				(width 0.1)
				(type default)
			)
			(layer "B.Fab")
		)
		(fp_line
			(start 0.299974 -0.150114)
			(end -0.299974 -0.150114)
			(stroke
				(width 0.1)
				(type default)
			)
			(layer "B.Fab")
		)
		(fp_line
			(start 0.299974 0.150114)
			(end 0.299974 -0.150114)
			(stroke
				(width 0.1)
				(type default)
			)
			(layer "B.Fab")
		)
		(pad "1" smd rect
			(at 0.2667 0 180)
			(size 0.3048 0.381)
			(layers "B.Cu" "B.Mask" "B.Paste")
			(net "P1V8_PEX")
		)
		(pad "2" smd rect
			(at -0.2667 0 180)
			(size 0.3048 0.381)
			(layers "B.Cu" "B.Mask" "B.Paste")
			(net "GND")
		)
	)
	(footprint ""
		(layer "B.Cu")
		(at 409.374848 -297.79976 -90)
		(property "Reference" "C1909"
			(at 0 0 90)
			(layer "B.SilkS")
			(hide yes)
			(effects
				(font
					(size 1.27 1.27)
				)
				(justify mirror)
			)
		)
		(property "Value" ""
			(at 0 0 90)
			(layer "B.Fab")
			(effects
				(font
					(size 1.27 1.27)
				)
				(justify mirror)
			)
		)
		(duplicate_pad_numbers_are_jumpers no)
		(fp_line
			(start -0.299974 0.150114)
			(end 0.299974 0.150114)
			(stroke
				(width 0.1)
				(type default)
			)
			(layer "B.Fab")
		)
		(fp_line
			(start 0.299974 0.150114)
			(end 0.299974 -0.150114)
			(stroke
				(width 0.1)
				(type default)
			)
			(layer "B.Fab")
		)
		(fp_line
			(start -0.299974 -0.150114)
			(end -0.299974 0.150114)
			(stroke
				(width 0.1)
				(type default)
			)
			(layer "B.Fab")
		)
		(fp_line
			(start 0.299974 -0.150114)
			(end -0.299974 -0.150114)
			(stroke
				(width 0.1)
				(type default)
			)
			(layer "B.Fab")
		)
		(pad "1" smd rect
			(at 0.2667 0 90)
			(size 0.3048 0.381)
			(layers "B.Cu" "B.Mask" "B.Paste")
			(net "P0V8_PEX3")
		)
		(pad "2" smd rect
			(at -0.2667 0 90)
			(size 0.3048 0.381)
			(layers "B.Cu" "B.Mask" "B.Paste")
			(net "GND")
		)
	)
)
